# S9S_MB_2U (Grand Teton) — schematic netlist excerpt (pin names and nets, part order shuffled) for the footprints in the layout excerpt that follows; sources: Cadence DE-HDL packaged netlist, KiCad conversion of 03242023_DA0F0TMBIJ0_F0T_Motherboard_J_brd_V01_OCP.brd

R342  Q_RES  0 5% CHIP  pkg 0402LF  page 225 : A = H_CPU_ERR1_LVC1_R_N ; B = H_CPU_ERR1_LVC1_N
R4214  Q_RES  0 5% CHIP  pkg 0402LF  page 170 : A = FM_THERMAL_ALERT_N ; B = FM_G751_1_ALERT_N
C765  Q_CAP_DIFFBUS  DIFF BUS_0.22UF 6.3V 20% X6S  pkg C0201  page 176 : \1\ = P5E_CPU1_PE2_TX_C_DP<4> ; \2\ = P5E_CPU1_PE2_TX_DP<4>

(kicad_pcb
	(version 20260206)
	(generator "pcbnew")
	(generator_version "10.0")
	(general
		(thickness 1.6)
		(legacy_teardrops no)
	)
	(paper "A4")
	(title_block
		(title "03242023_DA0F0TMBIJ0_F0T_Motherboard_J_brd_V01_OCP.brd")
		(comment 1 "Grand Teton / footprints 1767-1769 of 6105")
	)
	(layers
		(0 "F.Cu" signal "TOP")
		(4 "In1.Cu" signal "GND")
		(6 "In2.Cu" signal "IN1")
		(8 "In3.Cu" signal "GND1")
		(10 "In4.Cu" signal "IN2")
		(12 "In5.Cu" signal "GND2")
		(14 "In6.Cu" signal "IN3")
		(16 "In7.Cu" signal "GND3")
		(18 "In8.Cu" signal "VCC")
		(20 "In9.Cu" signal "VCC1")
		(22 "In10.Cu" signal "GND4")
		(24 "In11.Cu" signal "IN4")
		(26 "In12.Cu" signal "GND5")
		(28 "In13.Cu" signal "IN5")
		(30 "In14.Cu" signal "GND6")
		(32 "In15.Cu" signal "IN6")
		(34 "In16.Cu" signal "GND7")
		(2 "B.Cu" signal "BOTTOM")
		(9 "F.Adhes" user "F.Adhesive")
		(11 "B.Adhes" user "B.Adhesive")
		(13 "F.Paste" user "Package Geometry/Pastemask Top")
		(15 "B.Paste" user "Package Geometry/Pastemask Bottom")
		(5 "F.SilkS" user "Ref Des/Silkscreen Top")
		(7 "B.SilkS" user "Ref Des/Silkscreen Bottom")
		(1 "F.Mask" user "Board Geometry/Soldermask Top")
		(3 "B.Mask" user "Board Geometry/Soldermask Bottom")
		(17 "Dwgs.User" user "User.Drawings")
		(19 "Cmts.User" user "User.Comments")
		(21 "Eco1.User" user "User.Eco1")
		(23 "Eco2.User" user "User.Eco2")
		(25 "Edge.Cuts" user "Board Geometry/Outline")
		(27 "Margin" user)
		(31 "F.CrtYd" user "Package Geometry/Place Bound Top")
		(29 "B.CrtYd" user "Package Geometry/Place Bound Bottom")
		(35 "F.Fab" user "Ref Des/Assembly Top")
		(33 "B.Fab" user "Ref Des/Assembly Bottom")
	)
	(footprint ""
		(layer "F.Cu")
		(at 140.7922 -104.116378 -90)
		(property "Reference" "R342"
			(at 0 0 270)
			(layer "F.SilkS")
			(hide yes)
			(effects
				(font
					(size 1.27 1.27)
				)
			)
		)
		(property "Value" ""
			(at 0 0 270)
			(layer "F.Fab")
			(effects
				(font
					(size 1.27 1.27)
				)
			)
		)
		(duplicate_pad_numbers_are_jumpers no)
		(fp_line
			(start -0.7874 0.4064)
			(end -0.7874 -0.4064)
			(stroke
				(width 0.1524)
				(type default)
			)
			(layer "F.SilkS")
		)
		(fp_line
			(start 0.7874 0.4064)
			(end -0.7874 0.4064)
			(stroke
				(width 0.1524)
				(type default)
			)
			(layer "F.SilkS")
		)
		(fp_line
			(start -0.7874 -0.4064)
			(end 0.7874 -0.4064)
			(stroke
				(width 0.1524)
				(type default)
			)
			(layer "F.SilkS")
		)
		(fp_line
			(start 0.7874 -0.4064)
			(end 0.7874 0.4064)
			(stroke
				(width 0.1524)
				(type default)
			)
			(layer "F.SilkS")
		)
		(fp_line
			(start -0.67945 0.3048)
			(end -0.67945 -0.305054)
			(stroke
				(width 0.1)
				(type default)
			)
			(layer "F.Fab")
		)
		(fp_line
			(start -0.12065 0.3048)
			(end -0.67945 0.3048)
			(stroke
				(width 0.1)
				(type default)
			)
			(layer "F.Fab")
		)
		(fp_line
			(start 0.120396 0.3048)
			(end 0.120396 0.2794)
			(stroke
				(width 0.1)
				(type default)
			)
			(layer "F.Fab")
		)
		(fp_line
			(start 0.67945 0.3048)
			(end 0.120396 0.3048)
			(stroke
				(width 0.1)
				(type default)
			)
			(layer "F.Fab")
		)
		(fp_line
			(start -0.12065 0.2794)
			(end -0.12065 0.3048)
			(stroke
				(width 0.1)
				(type default)
			)
			(layer "F.Fab")
		)
		(fp_line
			(start 0.120396 0.2794)
			(end -0.12065 0.2794)
			(stroke
				(width 0.1)
				(type default)
			)
			(layer "F.Fab")
		)
		(fp_line
			(start -0.12065 -0.2794)
			(end 0.12065 -0.2794)
			(stroke
				(width 0.1)
				(type default)
			)
			(layer "F.Fab")
		)
		(fp_line
			(start 0.12065 -0.2794)
			(end 0.12065 -0.3048)
			(stroke
				(width 0.1)
				(type default)
			)
			(layer "F.Fab")
		)
		(fp_line
			(start 0.12065 -0.3048)
			(end 0.67945 -0.3048)
			(stroke
				(width 0.1)
				(type default)
			)
			(layer "F.Fab")
		)
		(fp_line
			(start 0.67945 -0.3048)
			(end 0.67945 0.3048)
			(stroke
				(width 0.1)
				(type default)
			)
			(layer "F.Fab")
		)
		(fp_line
			(start -0.67945 -0.305054)
			(end -0.12065 -0.305054)
			(stroke
				(width 0.1)
				(type default)
			)
			(layer "F.Fab")
		)
		(fp_line
			(start -0.12065 -0.305054)
			(end -0.12065 -0.2794)
			(stroke
				(width 0.1)
				(type default)
			)
			(layer "F.Fab")
		)
		(pad "1" smd circle
			(at -0.40005 0 270)
			(size 0 0)
			(layers "F.Cu" "F.Mask" "F.Paste")
			(net "H_CPU_ERR1_LVC1_R_N")
		)
		(pad "2" smd circle
			(at 0.40005 0 270)
			(size 0 0)
			(layers "F.Cu" "F.Mask" "F.Paste")
			(net "H_CPU_ERR1_LVC1_N")
		)
	)
	(footprint ""
		(layer "F.Cu")
		(at 285.242762 -14.36243)
		(property "Reference" "R4214"
			(at 0 0 0)
			(layer "F.SilkS")
			(hide yes)
			(effects
				(font
					(size 1.27 1.27)
				)
			)
		)
		(property "Value" ""
			(at 0 0 0)
			(layer "F.Fab")
			(effects
				(font
					(size 1.27 1.27)
				)
			)
		)
		(duplicate_pad_numbers_are_jumpers no)
		(fp_line
			(start -0.7874 -0.4064)
			(end 0.7874 -0.4064)
			(stroke
				(width 0.1524)
				(type default)
			)
			(layer "F.SilkS")
		)
		(fp_line
			(start -0.7874 0.4064)
			(end -0.7874 -0.4064)
			(stroke
				(width 0.1524)
				(type default)
			)
			(layer "F.SilkS")
		)
		(fp_line
			(start 0.7874 -0.4064)
			(end 0.7874 0.4064)
			(stroke
				(width 0.1524)
				(type default)
			)
			(layer "F.SilkS")
		)
		(fp_line
			(start 0.7874 0.4064)
			(end -0.7874 0.4064)
			(stroke
				(width 0.1524)
				(type default)
			)
			(layer "F.SilkS")
		)
		(fp_line
			(start -0.67945 -0.305054)
			(end -0.12065 -0.305054)
			(stroke
				(width 0.1)
				(type default)
			)
			(layer "F.Fab")
		)
		(fp_line
			(start -0.67945 0.3048)
			(end -0.67945 -0.305054)
			(stroke
				(width 0.1)
				(type default)
			)
			(layer "F.Fab")
		)
		(fp_line
			(start -0.12065 -0.305054)
			(end -0.12065 -0.2794)
			(stroke
				(width 0.1)
				(type default)
			)
			(layer "F.Fab")
		)
		(fp_line
			(start -0.12065 -0.2794)
			(end 0.12065 -0.2794)
			(stroke
				(width 0.1)
				(type default)
			)
			(layer "F.Fab")
		)
		(fp_line
			(start -0.12065 0.2794)
			(end -0.12065 0.3048)
			(stroke
				(width 0.1)
				(type default)
			)
			(layer "F.Fab")
		)
		(fp_line
			(start -0.12065 0.3048)
			(end -0.67945 0.3048)
			(stroke
				(width 0.1)
				(type default)
			)
			(layer "F.Fab")
		)
		(fp_line
			(start 0.120396 0.2794)
			(end -0.12065 0.2794)
			(stroke
				(width 0.1)
				(type default)
			)
			(layer "F.Fab")
		)
		(fp_line
			(start 0.120396 0.3048)
			(end 0.120396 0.2794)
			(stroke
				(width 0.1)
				(type default)
			)
			(layer "F.Fab")
		)
		(fp_line
			(start 0.12065 -0.3048)
			(end 0.67945 -0.3048)
			(stroke
				(width 0.1)
				(type default)
			)
			(layer "F.Fab")
		)
		(fp_line
			(start 0.12065 -0.2794)
			(end 0.12065 -0.3048)
			(stroke
				(width 0.1)
				(type default)
			)
			(layer "F.Fab")
		)
		(fp_line
			(start 0.67945 -0.3048)
			(end 0.67945 0.3048)
			(stroke
				(width 0.1)
				(type default)
			)
			(layer "F.Fab")
		)
		(fp_line
			(start 0.67945 0.3048)
			(end 0.120396 0.3048)
			(stroke
				(width 0.1)
				(type default)
			)
			(layer "F.Fab")
		)
		(pad "1" smd circle
			(at -0.40005 0)
			(size 0 0)
			(layers "F.Cu" "F.Mask" "F.Paste")
			(net "FM_THERMAL_ALERT_N")
		)
		(pad "2" smd circle
			(at 0.40005 0)
			(size 0 0)
			(layers "F.Cu" "F.Mask" "F.Paste")
			(net "FM_G751_1_ALERT_N")
		)
	)
	(footprint ""
		(layer "F.Cu")
		(at 153.825194 -402.371052 -90)
		(property "Reference" "C765"
			(at 0 0 270)
			(layer "F.SilkS")
			(hide yes)
			(effects
				(font
					(size 1.27 1.27)
				)
			)
		)
		(property "Value" ""
			(at 0 0 270)
			(layer "F.Fab")
			(effects
				(font
					(size 1.27 1.27)
				)
			)
		)
		(duplicate_pad_numbers_are_jumpers no)
		(fp_line
			(start -0.299974 0.150114)
			(end -0.299974 -0.150114)
			(stroke
				(width 0.1)
				(type default)
			)
			(layer "F.Fab")
		)
		(fp_line
			(start 0.299974 0.150114)
			(end -0.299974 0.150114)
			(stroke
				(width 0.1)
				(type default)
			)
			(layer "F.Fab")
		)
		(fp_line
			(start -0.299974 -0.150114)
			(end 0.299974 -0.150114)
			(stroke
				(width 0.1)
				(type default)
			)
			(layer "F.Fab")
		)
		(fp_line
			(start 0.299974 -0.150114)
			(end 0.299974 0.150114)
			(stroke
				(width 0.1)
				(type default)
			)
			(layer "F.Fab")
		)
		(pad "1" smd rect
			(at -0.2667 0 270)
			(size 0.3048 0.381)
			(layers "F.Cu" "F.Mask" "F.Paste")
			(net "P5E_CPU1_PE2_TX_C_DP<4>")
		)
		(pad "2" smd rect
			(at 0.2667 0 270)
			(size 0.3048 0.381)
			(layers "F.Cu" "F.Mask" "F.Paste")
			(net "P5E_CPU1_PE2_TX_DP<4>")
		)
	)
)
